(kicad_pcb
	(version 20241229)
	(generator "pcbnew")
	(generator_version "9.0")
	(general
		(thickness 1.294)
		(legacy_teardrops no)
	)
	(paper "A3")
	(title_block
		(title "Kintex 410T devboard")
		(date "2024-04-03")
		(rev "1.1.2")
		(comment 9 "footprints 759-764 of 975")
	)
	(layers
		(0 "F.Cu" mixed)
		(4 "In1.Cu" power)
		(6 "In2.Cu" power)
		(8 "In3.Cu" mixed)
		(10 "In4.Cu" power)
		(12 "In5.Cu" mixed)
		(14 "In6.Cu" power)
		(16 "In7.Cu" mixed)
		(18 "In8.Cu" power)
		(2 "B.Cu" mixed)
		(9 "F.Adhes" user "F.Adhesive")
		(11 "B.Adhes" user "B.Adhesive")
		(13 "F.Paste" user)
		(15 "B.Paste" user)
		(5 "F.SilkS" user "F.Silkscreen")
		(7 "B.SilkS" user "B.Silkscreen")
		(1 "F.Mask" user)
		(3 "B.Mask" user)
		(17 "Dwgs.User" user "User.Drawings")
		(19 "Cmts.User" user "User.Comments")
		(21 "Eco1.User" user "User.Eco1")
		(23 "Eco2.User" user "User.Eco2")
		(25 "Edge.Cuts" user)
		(27 "Margin" user)
		(31 "F.CrtYd" user "F.Courtyard")
		(29 "B.CrtYd" user "B.Courtyard")
		(35 "F.Fab" user)
		(33 "B.Fab" user)
	)
	(footprint "antmicro-footprints:C_0402_1005Metric"
		(layer "B.Cu")
		(at 211 123.5 180)
		(descr "Capacitor SMD 0402")
		(tags "capacitor SMD 0402")
		(property "Reference" "C38"
			(at -1 0.475 0)
			(layer "B.SilkS")
			(effects
				(font
					(size 0.7 0.7)
					(thickness 0.15)
				)
				(justify left bottom mirror)
			)
		)
		(property "Value" "C_100n_0402"
			(at 0 -1.169 0)
			(layer "B.Fab")
			(effects
				(font
					(size 0.7 0.7)
					(thickness 0.15)
				)
				(justify left bottom mirror)
			)
		)
		(property "Description" "SMD Multilayer Ceramic Capacitor, 0.1 µF, 50 V, 0402 [1005 Metric], ± 10%, X5R, GRM Series"
			(at 0 0 180)
			(layer "F.Fab")
			(hide yes)
			(effects
				(font
					(size 1.27 1.27)
					(thickness 0.15)
				)
			)
		)
		(property "Author" "Antmicro"
			(at 422 247 0)
			(layer "B.Fab")
			(hide yes)
			(effects
				(font
					(size 1 1)
					(thickness 0.15)
				)
				(justify mirror)
			)
		)
		(property "Dielectric" "X5R"
			(at 422 247 0)
			(layer "B.Fab")
			(hide yes)
			(effects
				(font
					(size 1 1)
					(thickness 0.15)
				)
				(justify mirror)
			)
		)
		(property "License" "Apache-2.0"
			(at 422 247 0)
			(layer "B.Fab")
			(hide yes)
			(effects
				(font
					(size 1 1)
					(thickness 0.15)
				)
				(justify mirror)
			)
		)
		(property "MPN" "GRM155R61H104KE14D"
			(at 422 247 0)
			(layer "B.Fab")
			(hide yes)
			(effects
				(font
					(size 1 1)
					(thickness 0.15)
				)
				(justify mirror)
			)
		)
		(property "Manufacturer" "Murata"
			(at 422 247 0)
			(layer "B.Fab")
			(hide yes)
			(effects
				(font
					(size 1 1)
					(thickness 0.15)
				)
				(justify mirror)
			)
		)
		(property "Val" "100n"
			(at 422 247 0)
			(layer "B.Fab")
			(hide yes)
			(effects
				(font
					(size 1 1)
					(thickness 0.15)
				)
				(justify mirror)
			)
		)
		(property "Voltage" "50V"
			(at 422 247 0)
			(layer "B.Fab")
			(hide yes)
			(effects
				(font
					(size 1 1)
					(thickness 0.15)
				)
				(justify mirror)
			)
		)
		(sheetname "FPGA Bank 14 & 15")
		(sheetfile "fpga-bank-14-15.kicad_sch")
		(attr smd)
		(fp_rect
			(start -0.925 0.47)
			(end 0.925 -0.47)
			(stroke
				(width 0.05)
				(type default)
			)
			(fill no)
			(layer "B.CrtYd")
		)
		(fp_line
			(start 0.504 0.25)
			(end 0.504 -0.248)
			(stroke
				(width 0.15)
				(type solid)
			)
			(layer "B.Fab")
		)
		(fp_line
			(start 0.504 -0.248)
			(end -0.494 -0.248)
			(stroke
				(width 0.15)
				(type solid)
			)
			(layer "B.Fab")
		)
		(fp_line
			(start -0.494 0.25)
			(end 0.504 0.25)
			(stroke
				(width 0.15)
				(type solid)
			)
			(layer "B.Fab")
		)
		(fp_line
			(start -0.494 -0.248)
			(end -0.494 0.25)
			(stroke
				(width 0.15)
				(type solid)
			)
			(layer "B.Fab")
		)
		(pad "1" smd roundrect
			(at -0.48 0 180)
			(size 0.59 0.64)
			(layers "B.Cu" "B.Mask" "B.Paste")
			(roundrect_rratio 0.25)
			(net 1 "GND")
			(pintype "passive")
		)
		(pad "2" smd roundrect
			(at 0.48 0 180)
			(size 0.59 0.64)
			(layers "B.Cu" "B.Mask" "B.Paste")
			(roundrect_rratio 0.25)
			(net 2 "VCC_USR_A")
			(pintype "passive")
		)
	)
	(footprint "antmicro-footprints:R_0402_1005Metric"
		(layer "B.Cu")
		(at 167.55 185.95 -90)
		(descr "Resistor SMD 0402")
		(tags "resistor SMD 0402")
		(property "Reference" "R321"
			(at -3.625 -0.525 90)
			(layer "B.SilkS")
			(effects
				(font
					(size 0.7 0.7)
					(thickness 0.15)
				)
				(justify left bottom mirror)
			)
		)
		(property "Value" "R_47k_0402"
			(at 0 -1.4 90)
			(layer "B.Fab")
			(effects
				(font
					(size 0.7 0.7)
					(thickness 0.15)
				)
				(justify left bottom mirror)
			)
		)
		(property "Description" "SMD Chip Resistor, 47 kohm, ± 1%, 62.5 mW, 0402 [1005 Metric], Thick Film, General Purpose"
			(at 0 0 270)
			(layer "F.Fab")
			(hide yes)
			(effects
				(font
					(size 1.27 1.27)
					(thickness 0.15)
				)
			)
		)
		(property "Author" "Antmicro"
			(at -18.4 353.5 0)
			(layer "B.Fab")
			(hide yes)
			(effects
				(font
					(size 1 1)
					(thickness 0.15)
				)
				(justify mirror)
			)
		)
		(property "License" "Apache-2.0"
			(at -18.4 353.5 0)
			(layer "B.Fab")
			(hide yes)
			(effects
				(font
					(size 1 1)
					(thickness 0.15)
				)
				(justify mirror)
			)
		)
		(property "MPN" "CR0402-FX-4702GLF"
			(at -18.4 353.5 0)
			(layer "B.Fab")
			(hide yes)
			(effects
				(font
					(size 1 1)
					(thickness 0.15)
				)
				(justify mirror)
			)
		)
		(property "Manufacturer" "Bourns"
			(at -18.4 353.5 0)
			(layer "B.Fab")
			(hide yes)
			(effects
				(font
					(size 1 1)
					(thickness 0.15)
				)
				(justify mirror)
			)
		)
		(property "Tolerance" "1%"
			(at -18.4 353.5 0)
			(layer "B.Fab")
			(hide yes)
			(effects
				(font
					(size 1 1)
					(thickness 0.15)
				)
				(justify mirror)
			)
		)
		(property "Val" "47k"
			(at -18.4 353.5 0)
			(layer "B.Fab")
			(hide yes)
			(effects
				(font
					(size 1 1)
					(thickness 0.15)
				)
				(justify mirror)
			)
		)
		(sheetname "DC-DC Converters")
		(sheetfile "dc-dc.kicad_sch")
		(attr smd)
		(fp_rect
			(start -0.925 0.47)
			(end 0.925 -0.47)
			(stroke
				(width 0.05)
				(type default)
			)
			(fill no)
			(layer "B.CrtYd")
		)
		(fp_rect
			(start -0.5 0.25)
			(end 0.5 -0.25)
			(stroke
				(width 0.15)
				(type solid)
			)
			(fill no)
			(layer "B.Fab")
		)
		(pad "1" smd roundrect
			(at -0.48 0 270)
			(size 0.59 0.64)
			(layers "B.Cu" "B.Mask" "B.Paste")
			(roundrect_rratio 0.25)
			(net 967 "/DC-DC Converters/EN2")
			(pintype "passive")
		)
		(pad "2" smd roundrect
			(at 0.48 0 270)
			(size 0.59 0.64)
			(layers "B.Cu" "B.Mask" "B.Paste")
			(roundrect_rratio 0.25)
			(net 37 "+3V3_AON")
			(pintype "passive")
		)
	)
	(footprint "antmicro-footprints:C_0603_1608Metric"
		(layer "B.Cu")
		(at 200 139.2 90)
		(descr "Capacitor SMD 0603")
		(tags "capacitor 0603")
		(property "Reference" "C46"
			(at -1.025 -0.55 90)
			(layer "B.SilkS")
			(effects
				(font
					(size 0.7 0.7)
					(thickness 0.15)
				)
				(justify right bottom mirror)
			)
		)
		(property "Value" "C_47u_0603"
			(at 0 -1.6 90)
			(layer "B.Fab")
			(effects
				(font
					(size 0.7 0.7)
					(thickness 0.15)
				)
				(justify right bottom mirror)
			)
		)
		(property "Description" "SMD Multilayer Ceramic Capacitor, 47 µF, 6.3 V, 0603 [1608 Metric], ± 20%, X5R, GRM Series"
			(at 0 0 90)
			(layer "F.Fab")
			(hide yes)
			(effects
				(font
					(size 1.27 1.27)
					(thickness 0.15)
				)
			)
		)
		(property "Author" "Antmicro"
			(at 339.2 -60.8 0)
			(layer "B.Fab")
			(hide yes)
			(effects
				(font
					(size 1 1)
					(thickness 0.15)
				)
				(justify mirror)
			)
		)
		(property "Dielectric" ""
			(at 339.2 -60.8 0)
			(layer "B.Fab")
			(hide yes)
			(effects
				(font
					(size 1 1)
					(thickness 0.15)
				)
				(justify mirror)
			)
		)
		(property "License" "Apache-2.0"
			(at 339.2 -60.8 0)
			(layer "B.Fab")
			(hide yes)
			(effects
				(font
					(size 1 1)
					(thickness 0.15)
				)
				(justify mirror)
			)
		)
		(property "MPN" "GRM188R60J476ME15D"
			(at 339.2 -60.8 0)
			(layer "B.Fab")
			(hide yes)
			(effects
				(font
					(size 1 1)
					(thickness 0.15)
				)
				(justify mirror)
			)
		)
		(property "Manufacturer" "Murata"
			(at 339.2 -60.8 0)
			(layer "B.Fab")
			(hide yes)
			(effects
				(font
					(size 1 1)
					(thickness 0.15)
				)
				(justify mirror)
			)
		)
		(property "Val" "47u"
			(at 339.2 -60.8 0)
			(layer "B.Fab")
			(hide yes)
			(effects
				(font
					(size 1 1)
					(thickness 0.15)
				)
				(justify mirror)
			)
		)
		(property "Voltage" ""
			(at 339.2 -60.8 0)
			(layer "B.Fab")
			(hide yes)
			(effects
				(font
					(size 1 1)
					(thickness 0.15)
				)
				(justify mirror)
			)
		)
		(sheetname "FPGA supply")
		(sheetfile "fpga-supply.kicad_sch")
		(attr smd)
		(fp_line
			(start -0.15 -0.4)
			(end 0.15 -0.4)
			(stroke
				(width 0.15)
				(type solid)
			)
			(layer "B.SilkS")
		)
		(fp_line
			(start -0.15 0.4)
			(end 0.15 0.4)
			(stroke
				(width 0.15)
				(type solid)
			)
			(layer "B.SilkS")
		)
		(fp_rect
			(start -1.25 0.65)
			(end 1.25 -0.65)
			(stroke
				(width 0.05)
				(type solid)
			)
			(fill no)
			(layer "B.CrtYd")
		)
		(fp_rect
			(start -0.8 0.4)
			(end 0.8 -0.4)
			(stroke
				(width 0.15)
				(type solid)
			)
			(fill no)
			(layer "B.Fab")
		)
		(pad "1" smd roundrect
			(at -0.7 0 90)
			(size 0.8 1)
			(layers "B.Cu" "B.Mask" "B.Paste")
			(roundrect_rratio 0.2)
			(net 1 "GND")
			(pintype "passive")
		)
		(pad "2" smd roundrect
			(at 0.7 0 90)
			(size 0.8 1)
			(layers "B.Cu" "B.Mask" "B.Paste")
			(roundrect_rratio 0.2)
			(net 26 "+1V8")
			(pintype "passive")
		)
	)
	(footprint "antmicro-footprints:R_0402_1005Metric"
		(layer "B.Cu")
		(at 261.5 81.4)
		(descr "Resistor SMD 0402")
		(tags "resistor SMD 0402")
		(property "Reference" "R131"
			(at 1.45 1.25 180)
			(layer "B.SilkS")
			(effects
				(font
					(size 0.7 0.7)
					(thickness 0.15)
				)
				(justify left bottom mirror)
			)
		)
		(property "Value" "R_1k_0402"
			(at 0 -1.4 180)
			(layer "B.Fab")
			(effects
				(font
					(size 0.7 0.7)
					(thickness 0.15)
				)
				(justify left bottom mirror)
			)
		)
		(property "Description" "SMD Chip Resistor, 1 kohm, ± 1%, 63 mW, 0402 [1005 Metric], Thick Film, General Purpose"
			(at 0 0 0)
			(layer "F.Fab")
			(hide yes)
			(effects
				(font
					(size 1.27 1.27)
					(thickness 0.15)
				)
			)
		)
		(property "Author" "Antmicro"
			(at 0 0 0)
			(layer "B.Fab")
			(hide yes)
			(effects
				(font
					(size 1 1)
					(thickness 0.15)
				)
				(justify mirror)
			)
		)
		(property "License" "Apache-2.0"
			(at 0 0 0)
			(layer "B.Fab")
			(hide yes)
			(effects
				(font
					(size 1 1)
					(thickness 0.15)
				)
				(justify mirror)
			)
		)
		(property "MPN" "CR0402-FX-1001GLF"
			(at 0 0 0)
			(layer "B.Fab")
			(hide yes)
			(effects
				(font
					(size 1 1)
					(thickness 0.15)
				)
				(justify mirror)
			)
		)
		(property "Manufacturer" "Bourns"
			(at 0 0 0)
			(layer "B.Fab")
			(hide yes)
			(effects
				(font
					(size 1 1)
					(thickness 0.15)
				)
				(justify mirror)
			)
		)
		(property "Tolerance" "1%"
			(at 0 0 0)
			(layer "B.Fab")
			(hide yes)
			(effects
				(font
					(size 1 1)
					(thickness 0.15)
				)
				(justify mirror)
			)
		)
		(property "Val" "1k"
			(at 0 0 0)
			(layer "B.Fab")
			(hide yes)
			(effects
				(font
					(size 1 1)
					(thickness 0.15)
				)
				(justify mirror)
			)
		)
		(sheetname "User GPIO + LED + button + DIP switch")
		(sheetfile "user-gpio.kicad_sch")
		(attr smd)
		(fp_rect
			(start -0.925 0.47)
			(end 0.925 -0.47)
			(stroke
				(width 0.05)
				(type default)
			)
			(fill no)
			(layer "B.CrtYd")
		)
		(fp_rect
			(start -0.5 0.25)
			(end 0.5 -0.25)
			(stroke
				(width 0.15)
				(type solid)
			)
			(fill no)
			(layer "B.Fab")
		)
		(pad "1" smd roundrect
			(at -0.48 0)
			(size 0.59 0.64)
			(layers "B.Cu" "B.Mask" "B.Paste")
			(roundrect_rratio 0.25)
			(net 24 "+3V3")
			(pintype "passive")
		)
		(pad "2" smd roundrect
			(at 0.48 0)
			(size 0.59 0.64)
			(layers "B.Cu" "B.Mask" "B.Paste")
			(roundrect_rratio 0.25)
			(net 789 "Net-(D25-A)")
			(pintype "passive")
		)
	)
	(footprint "antmicro-footprints:C_0402_1005Metric"
		(layer "B.Cu")
		(at 208.5 132 90)
		(descr "Capacitor SMD 0402")
		(tags "capacitor SMD 0402")
		(property "Reference" "C31"
			(at 0.75 1.2 270)
			(layer "B.SilkS")
			(effects
				(font
					(size 0.7 0.7)
					(thickness 0.15)
				)
				(justify left bottom mirror)
			)
		)
		(property "Value" "C_100n_0402"
			(at 0 -1.169 270)
			(layer "B.Fab")
			(effects
				(font
					(size 0.7 0.7)
					(thickness 0.15)
				)
				(justify left bottom mirror)
			)
		)
		(property "Description" "SMD Multilayer Ceramic Capacitor, 0.1 µF, 50 V, 0402 [1005 Metric], ± 10%, X5R, GRM Series"
			(at 0 0 90)
			(layer "F.Fab")
			(hide yes)
			(effects
				(font
					(size 1.27 1.27)
					(thickness 0.15)
				)
			)
		)
		(property "Author" "Antmicro"
			(at 340.5 -76.5 0)
			(layer "B.Fab")
			(hide yes)
			(effects
				(font
					(size 1 1)
					(thickness 0.15)
				)
				(justify mirror)
			)
		)
		(property "Dielectric" "X5R"
			(at 340.5 -76.5 0)
			(layer "B.Fab")
			(hide yes)
			(effects
				(font
					(size 1 1)
					(thickness 0.15)
				)
				(justify mirror)
			)
		)
		(property "License" "Apache-2.0"
			(at 340.5 -76.5 0)
			(layer "B.Fab")
			(hide yes)
			(effects
				(font
					(size 1 1)
					(thickness 0.15)
				)
				(justify mirror)
			)
		)
		(property "MPN" "GRM155R61H104KE14D"
			(at 340.5 -76.5 0)
			(layer "B.Fab")
			(hide yes)
			(effects
				(font
					(size 1 1)
					(thickness 0.15)
				)
				(justify mirror)
			)
		)
		(property "Manufacturer" "Murata"
			(at 340.5 -76.5 0)
			(layer "B.Fab")
			(hide yes)
			(effects
				(font
					(size 1 1)
					(thickness 0.15)
				)
				(justify mirror)
			)
		)
		(property "Val" "100n"
			(at 340.5 -76.5 0)
			(layer "B.Fab")
			(hide yes)
			(effects
				(font
					(size 1 1)
					(thickness 0.15)
				)
				(justify mirror)
			)
		)
		(property "Voltage" "50V"
			(at 340.5 -76.5 0)
			(layer "B.Fab")
			(hide yes)
			(effects
				(font
					(size 1 1)
					(thickness 0.15)
				)
				(justify mirror)
			)
		)
		(sheetname "FPGA Bank 14 & 15")
		(sheetfile "fpga-bank-14-15.kicad_sch")
		(attr smd)
		(fp_rect
			(start -0.925 0.47)
			(end 0.925 -0.47)
			(stroke
				(width 0.05)
				(type default)
			)
			(fill no)
			(layer "B.CrtYd")
		)
		(fp_line
			(start 0.504 -0.248)
			(end -0.494 -0.248)
			(stroke
				(width 0.15)
				(type solid)
			)
			(layer "B.Fab")
		)
		(fp_line
			(start -0.494 -0.248)
			(end -0.494 0.25)
			(stroke
				(width 0.15)
				(type solid)
			)
			(layer "B.Fab")
		)
		(fp_line
			(start 0.504 0.25)
			(end 0.504 -0.248)
			(stroke
				(width 0.15)
				(type solid)
			)
			(layer "B.Fab")
		)
		(fp_line
			(start -0.494 0.25)
			(end 0.504 0.25)
			(stroke
				(width 0.15)
				(type solid)
			)
			(layer "B.Fab")
		)
		(pad "1" smd roundrect
			(at -0.48 0 90)
			(size 0.59 0.64)
			(layers "B.Cu" "B.Mask" "B.Paste")
			(roundrect_rratio 0.25)
			(net 1 "GND")
			(pintype "passive")
		)
		(pad "2" smd roundrect
			(at 0.48 0 90)
			(size 0.59 0.64)
			(layers "B.Cu" "B.Mask" "B.Paste")
			(roundrect_rratio 0.25)
			(net 24 "+3V3")
			(pintype "passive")
		)
	)
	(footprint "antmicro-footprints:R_0402_1005Metric"
		(layer "B.Cu")
		(at 225.626 149.217)
		(descr "Resistor SMD 0402")
		(tags "resistor SMD 0402")
		(property "Reference" "R226"
			(at 3.599 0.358 180)
			(layer "B.SilkS")
			(effects
				(font
					(size 0.7 0.7)
					(thickness 0.15)
				)
				(justify left bottom mirror)
			)
		)
		(property "Value" "R_2k2_0402"
			(at 0 -1.4 180)
			(layer "B.Fab")
			(effects
				(font
					(size 0.7 0.7)
					(thickness 0.15)
				)
				(justify left bottom mirror)
			)
		)
		(property "Description" "SMD Chip Resistor, 2.2 kohm, ± 1%, 62.5 mW, 0402 [1005 Metric], Thick Film, General Purpose"
			(at 0 0 0)
			(layer "F.Fab")
			(hide yes)
			(effects
				(font
					(size 1.27 1.27)
					(thickness 0.15)
				)
			)
		)
		(property "Author" "Antmicro"
			(at 0 0 0)
			(layer "B.Fab")
			(hide yes)
			(effects
				(font
					(size 1 1)
					(thickness 0.15)
				)
				(justify mirror)
			)
		)
		(property "DNP" "DNP"
			(at 0 0 0)
			(layer "B.Fab")
			(hide yes)
			(effects
				(font
					(size 1 1)
					(thickness 0.15)
				)
				(justify mirror)
			)
		)
		(property "License" "Apache-2.0"
			(at 0 0 0)
			(layer "B.Fab")
			(hide yes)
			(effects
				(font
					(size 1 1)
					(thickness 0.15)
				)
				(justify mirror)
			)
		)
		(property "MPN" "CR0402-FX-2201GLF"
			(at 0 0 0)
			(layer "B.Fab")
			(hide yes)
			(effects
				(font
					(size 1 1)
					(thickness 0.15)
				)
				(justify mirror)
			)
		)
		(property "Manufacturer" "Bourns"
			(at 0 0 0)
			(layer "B.Fab")
			(hide yes)
			(effects
				(font
					(size 1 1)
					(thickness 0.15)
				)
				(justify mirror)
			)
		)
		(property "Tolerance" "1%"
			(at 0 0 0)
			(layer "B.Fab")
			(hide yes)
			(effects
				(font
					(size 1 1)
					(thickness 0.15)
				)
				(justify mirror)
			)
		)
		(property "Val" "2k2"
			(at 0 0 0)
			(layer "B.Fab")
			(hide yes)
			(effects
				(font
					(size 1 1)
					(thickness 0.15)
				)
				(justify mirror)
			)
		)
		(property "dnp" ""
			(at 0 0 0)
			(layer "B.Fab")
			(hide yes)
			(effects
				(font
					(size 1 1)
					(thickness 0.15)
				)
				(justify mirror)
			)
		)
		(property "exclude_from_bom" ""
			(at 0 0 0)
			(layer "B.Fab")
			(hide yes)
			(effects
				(font
					(size 1 1)
					(thickness 0.15)
				)
				(justify mirror)
			)
		)
		(sheetname "HDMI + Ethernet")
		(sheetfile "hdmi-ethernet.kicad_sch")
		(attr smd exclude_from_bom)
		(fp_rect
			(start -0.925 0.47)
			(end 0.925 -0.47)
			(stroke
				(width 0.05)
				(type default)
			)
			(fill no)
			(layer "B.CrtYd")
		)
		(fp_rect
			(start -0.5 0.25)
			(end 0.5 -0.25)
			(stroke
				(width 0.15)
				(type solid)
			)
			(fill no)
			(layer "B.Fab")
		)
		(pad "1" smd roundrect
			(at -0.48 0)
			(size 0.59 0.64)
			(layers "B.Cu" "B.Mask" "B.Paste")
			(roundrect_rratio 0.25)
			(net 945 "/HDMI + Ethernet/ETH_PHY_RXD1")
			(pintype "passive")
		)
		(pad "2" smd roundrect
			(at 0.48 0)
			(size 0.59 0.64)
			(layers "B.Cu" "B.Mask" "B.Paste")
			(roundrect_rratio 0.25)
			(net 1 "GND")
			(pintype "passive")
		)
	)
)
